# T6G (Grand Teton) — schematic netlist excerpt (pin names and nets, part order shuffled) for the footprints in the layout excerpt that follows; sources: Cadence DE-HDL packaged netlist, KiCad conversion of 04192023_DAF0TMB3IC0_F0TG_MB_C_brd_V02_OCP.brd

R8106  Q_RES  1K 1% CHIP  pkg 0402LF  page 242 : A = P3V3_AUX ; B = FM_AC_PWR_BTN_PLD_ISO_N
R6762  Q_RES  1K 1% CHIP  pkg 0201LF  page 184 : A = P1V8_CPU0_RT_1D ; B = SMB_RT_CPU0_P0_R_SDA
C6098  Q_CAP  0.1UF 25V 10% X7R  pkg 0402  page 179 : A = P3V3_AUX_CPU0_USB2_AVDD33 ; B = GND

(kicad_pcb
	(version 20260206)
	(generator "pcbnew")
	(generator_version "10.0")
	(general
		(thickness 1.6)
		(legacy_teardrops no)
	)
	(paper "A4")
	(title_block
		(title "04192023_DAF0TMB3IC0_F0TG_MB_C_brd_V02_OCP.brd")
		(comment 1 "Grand Teton / footprints 7383-7385 of 8354")
	)
	(layers
		(0 "F.Cu" signal "TOP")
		(4 "In1.Cu" signal "GND")
		(6 "In2.Cu" signal "IN1")
		(8 "In3.Cu" signal "GND1")
		(10 "In4.Cu" signal "IN2")
		(12 "In5.Cu" signal "GND2")
		(14 "In6.Cu" signal "IN3")
		(16 "In7.Cu" signal "GND3")
		(18 "In8.Cu" signal "VCC")
		(20 "In9.Cu" signal "VCC1")
		(22 "In10.Cu" signal "GND4")
		(24 "In11.Cu" signal "IN4")
		(26 "In12.Cu" signal "GND5")
		(28 "In13.Cu" signal "IN5")
		(30 "In14.Cu" signal "GND6")
		(32 "In15.Cu" signal "IN6")
		(34 "In16.Cu" signal "GND7")
		(2 "B.Cu" signal "BOTTOM")
		(9 "F.Adhes" user "F.Adhesive")
		(11 "B.Adhes" user "B.Adhesive")
		(13 "F.Paste" user "Package Geometry/Pastemask Top")
		(15 "B.Paste" user "Package Geometry/Pastemask Bottom")
		(5 "F.SilkS" user "Ref Des/Silkscreen Top")
		(7 "B.SilkS" user "Ref Des/Silkscreen Bottom")
		(1 "F.Mask" user "Board Geometry/Soldermask Top")
		(3 "B.Mask" user "Board Geometry/Soldermask Bottom")
		(17 "Dwgs.User" user "User.Drawings")
		(19 "Cmts.User" user "User.Comments")
		(21 "Eco1.User" user "User.Eco1")
		(23 "Eco2.User" user "User.Eco2")
		(25 "Edge.Cuts" user "Board Geometry/Outline")
		(27 "Margin" user)
		(31 "F.CrtYd" user "Package Geometry/Place Bound Top")
		(29 "B.CrtYd" user "Package Geometry/Place Bound Bottom")
		(35 "F.Fab" user "Ref Des/Assembly Top")
		(33 "B.Fab" user "Ref Des/Assembly Bottom")
	)
	(footprint ""
		(layer "B.Cu")
		(at 199.517 -134.874 -90)
		(property "Reference" "R8106"
			(at 0 0 90)
			(layer "B.SilkS")
			(hide yes)
			(effects
				(font
					(size 1.27 1.27)
				)
				(justify mirror)
			)
		)
		(property "Value" ""
			(at 0 0 90)
			(layer "B.Fab")
			(effects
				(font
					(size 1.27 1.27)
				)
				(justify mirror)
			)
		)
		(duplicate_pad_numbers_are_jumpers no)
		(fp_line
			(start -0.7874 0.4064)
			(end 0.7874 0.4064)
			(stroke
				(width 0.1524)
				(type default)
			)
			(layer "B.SilkS")
		)
		(fp_line
			(start 0.7874 0.4064)
			(end 0.7874 -0.4064)
			(stroke
				(width 0.1524)
				(type default)
			)
			(layer "B.SilkS")
		)
		(fp_line
			(start -0.7874 -0.4064)
			(end -0.7874 0.4064)
			(stroke
				(width 0.1524)
				(type default)
			)
			(layer "B.SilkS")
		)
		(fp_line
			(start 0.7874 -0.4064)
			(end -0.7874 -0.4064)
			(stroke
				(width 0.1524)
				(type default)
			)
			(layer "B.SilkS")
		)
		(fp_line
			(start -0.67945 0.3048)
			(end -0.120396 0.3048)
			(stroke
				(width 0.1)
				(type default)
			)
			(layer "B.Fab")
		)
		(fp_line
			(start -0.120396 0.3048)
			(end -0.120396 0.2794)
			(stroke
				(width 0.1)
				(type default)
			)
			(layer "B.Fab")
		)
		(fp_line
			(start 0.12065 0.3048)
			(end 0.67945 0.3048)
			(stroke
				(width 0.1)
				(type default)
			)
			(layer "B.Fab")
		)
		(fp_line
			(start 0.67945 0.3048)
			(end 0.67945 -0.305054)
			(stroke
				(width 0.1)
				(type default)
			)
			(layer "B.Fab")
		)
		(fp_line
			(start -0.120396 0.2794)
			(end 0.12065 0.2794)
			(stroke
				(width 0.1)
				(type default)
			)
			(layer "B.Fab")
		)
		(fp_line
			(start 0.12065 0.2794)
			(end 0.12065 0.3048)
			(stroke
				(width 0.1)
				(type default)
			)
			(layer "B.Fab")
		)
		(fp_line
			(start -0.12065 -0.2794)
			(end -0.12065 -0.3048)
			(stroke
				(width 0.1)
				(type default)
			)
			(layer "B.Fab")
		)
		(fp_line
			(start 0.12065 -0.2794)
			(end -0.12065 -0.2794)
			(stroke
				(width 0.1)
				(type default)
			)
			(layer "B.Fab")
		)
		(fp_line
			(start -0.67945 -0.3048)
			(end -0.67945 0.3048)
			(stroke
				(width 0.1)
				(type default)
			)
			(layer "B.Fab")
		)
		(fp_line
			(start -0.12065 -0.3048)
			(end -0.67945 -0.3048)
			(stroke
				(width 0.1)
				(type default)
			)
			(layer "B.Fab")
		)
		(fp_line
			(start 0.12065 -0.305054)
			(end 0.12065 -0.2794)
			(stroke
				(width 0.1)
				(type default)
			)
			(layer "B.Fab")
		)
		(fp_line
			(start 0.67945 -0.305054)
			(end 0.12065 -0.305054)
			(stroke
				(width 0.1)
				(type default)
			)
			(layer "B.Fab")
		)
		(pad "1" smd circle
			(at 0.40005 0 90)
			(size 0 0)
			(layers "B.Cu" "B.Mask" "B.Paste")
			(net "P3V3_AUX")
		)
		(pad "2" smd circle
			(at -0.40005 0 90)
			(size 0 0)
			(layers "B.Cu" "B.Mask" "B.Paste")
			(net "FM_AC_PWR_BTN_PLD_ISO_N")
		)
	)
	(footprint ""
		(layer "B.Cu")
		(at 231.648 -342.011 90)
		(property "Reference" "R6762"
			(at 0 0 90)
			(layer "B.SilkS")
			(hide yes)
			(effects
				(font
					(size 1.27 1.27)
				)
				(justify mirror)
			)
		)
		(property "Value" ""
			(at 0 0 90)
			(layer "B.Fab")
			(effects
				(font
					(size 1.27 1.27)
				)
				(justify mirror)
			)
		)
		(duplicate_pad_numbers_are_jumpers no)
		(fp_line
			(start 0.32512 -0.175006)
			(end -0.32512 -0.175006)
			(stroke
				(width 0.1)
				(type default)
			)
			(layer "B.Fab")
		)
		(fp_line
			(start -0.32512 -0.175006)
			(end -0.32512 0.175006)
			(stroke
				(width 0.1)
				(type default)
			)
			(layer "B.Fab")
		)
		(fp_line
			(start 0.32512 0.175006)
			(end 0.32512 -0.175006)
			(stroke
				(width 0.1)
				(type default)
			)
			(layer "B.Fab")
		)
		(fp_line
			(start -0.32512 0.175006)
			(end 0.32512 0.175006)
			(stroke
				(width 0.1)
				(type default)
			)
			(layer "B.Fab")
		)
		(pad "1" smd rect
			(at 0.2667 0 270)
			(size 0.3048 0.381)
			(layers "B.Cu" "B.Mask" "B.Paste")
			(net "P1V8_CPU0_RT_1D")
		)
		(pad "2" smd rect
			(at -0.2667 0 90)
			(size 0.3048 0.381)
			(layers "B.Cu" "B.Mask" "B.Paste")
			(net "SMB_RT_CPU0_P0_R_SDA")
		)
	)
	(footprint ""
		(layer "B.Cu")
		(at 110.965996 -26.952448 90)
		(property "Reference" "C6098"
			(at 0 0 90)
			(layer "B.SilkS")
			(hide yes)
			(effects
				(font
					(size 1.27 1.27)
				)
				(justify mirror)
			)
		)
		(property "Value" ""
			(at 0 0 90)
			(layer "B.Fab")
			(effects
				(font
					(size 1.27 1.27)
				)
				(justify mirror)
			)
		)
		(duplicate_pad_numbers_are_jumpers no)
		(fp_line
			(start 0.7874 -0.4064)
			(end -0.7874 -0.4064)
			(stroke
				(width 0.1524)
				(type default)
			)
			(layer "B.SilkS")
		)
		(fp_line
			(start -0.7874 -0.4064)
			(end -0.7874 0.4064)
			(stroke
				(width 0.1524)
				(type default)
			)
			(layer "B.SilkS")
		)
		(fp_line
			(start 0.7874 0.4064)
			(end 0.7874 -0.4064)
			(stroke
				(width 0.1524)
				(type default)
			)
			(layer "B.SilkS")
		)
		(fp_line
			(start -0.7874 0.4064)
			(end 0.7874 0.4064)
			(stroke
				(width 0.1524)
				(type default)
			)
			(layer "B.SilkS")
		)
		(fp_line
			(start 0.67945 -0.305054)
			(end 0.12065 -0.305054)
			(stroke
				(width 0.1)
				(type default)
			)
			(layer "B.Fab")
		)
		(fp_line
			(start 0.12065 -0.305054)
			(end 0.12065 -0.2794)
			(stroke
				(width 0.1)
				(type default)
			)
			(layer "B.Fab")
		)
		(fp_line
			(start -0.12065 -0.3048)
			(end -0.67945 -0.3048)
			(stroke
				(width 0.1)
				(type default)
			)
			(layer "B.Fab")
		)
		(fp_line
			(start -0.67945 -0.3048)
			(end -0.67945 0.3048)
			(stroke
				(width 0.1)
				(type default)
			)
			(layer "B.Fab")
		)
		(fp_line
			(start 0.12065 -0.2794)
			(end -0.12065 -0.2794)
			(stroke
				(width 0.1)
				(type default)
			)
			(layer "B.Fab")
		)
		(fp_line
			(start -0.12065 -0.2794)
			(end -0.12065 -0.3048)
			(stroke
				(width 0.1)
				(type default)
			)
			(layer "B.Fab")
		)
		(fp_line
			(start 0.12065 0.2794)
			(end 0.12065 0.3048)
			(stroke
				(width 0.1)
				(type default)
			)
			(layer "B.Fab")
		)
		(fp_line
			(start -0.120396 0.2794)
			(end 0.12065 0.2794)
			(stroke
				(width 0.1)
				(type default)
			)
			(layer "B.Fab")
		)
		(fp_line
			(start 0.67945 0.3048)
			(end 0.67945 -0.305054)
			(stroke
				(width 0.1)
				(type default)
			)
			(layer "B.Fab")
		)
		(fp_line
			(start 0.12065 0.3048)
			(end 0.67945 0.3048)
			(stroke
				(width 0.1)
				(type default)
			)
			(layer "B.Fab")
		)
		(fp_line
			(start -0.120396 0.3048)
			(end -0.120396 0.2794)
			(stroke
				(width 0.1)
				(type default)
			)
			(layer "B.Fab")
		)
		(fp_line
			(start -0.67945 0.3048)
			(end -0.120396 0.3048)
			(stroke
				(width 0.1)
				(type default)
			)
			(layer "B.Fab")
		)
		(pad "1" smd circle
			(at 0.40005 0 270)
			(size 0 0)
			(layers "B.Cu" "B.Mask" "B.Paste")
			(net "P3V3_AUX_CPU0_USB2_AVDD33")
		)
		(pad "2" smd circle
			(at -0.40005 0 270)
			(size 0 0)
			(layers "B.Cu" "B.Mask" "B.Paste")
			(net "GND")
		)
	)
)
